# BASEBOARD_FAB2 (Tioga Pass) — schematic netlist excerpt (pin names and nets, part order shuffled) for the footprints in the layout excerpt that follows; sources: Cadence DE-HDL packaged netlist, KiCad conversion of Wiwynn_Tioga_Pass_MB.brd

J6U2  SCONN288_H44441003  SCONN  pkg PIP  page 48
  \12v\(1)  = P12V_NVDIMM_ABC
  VSS(93)  = GND
  DQ(4)  = M_C_DQ<4>
  VSS(92)  = GND
  DQ(0)  = M_C_DQ<0>
  VSS(91)  = GND
  DQS9P  = M_C_DQS_DP<9>
  DQS9N  = M_C_DQS_DN<9>
  VSS(90)  = GND
  DQ(6)  = M_C_DQ<6>
  VSS(89)  = GND
  DQ(2)  = M_C_DQ<2>
  VSS(88)  = GND
  DQ(12)  = M_C_DQ<12>
  VSS(87)  = GND
  DQ(8)  = M_C_DQ<8>
  VSS(86)  = GND
  DQS10P  = M_C_DQS_DP<10>
  DQS10N  = M_C_DQS_DN<10>
  VSS(85)  = GND
  DQ(14)  = M_C_DQ<14>
  VSS(84)  = GND
  DQ(10)  = M_C_DQ<10>
  VSS(83)  = GND
  DQ(20)  = M_C_DQ<20>
  VSS(82)  = GND
  DQ(16)  = M_C_DQ<16>
  VSS(81)  = GND
  DQS11P  = M_C_DQS_DP<11>
  DQS11N  = M_C_DQS_DN<11>
  VSS(80)  = GND
  DQ(22)  = M_C_DQ<22>
  VSS(79)  = GND
  DQ(18)  = M_C_DQ<18>
  VSS(78)  = GND
  DQ(28)  = M_C_DQ<28>
  VSS(77)  = GND
  DQ(24)  = M_C_DQ<24>
  VSS(76)  = GND
  DQS12P  = M_C_DQS_DP<12>
  DQS12N  = M_C_DQS_DN<12>
  VSS(75)  = GND
  DQ(30)  = M_C_DQ<30>
  VSS(74)  = GND
  DQ(26)  = M_C_DQ<26>
  VSS(73)  = GND
  CB(4)  = M_C_ECC<4>
  VSS(72)  = GND
  CB(0)  = M_C_ECC<0>
  VSS(71)  = GND
  DQS17P  = M_C_DQS_DP<17>
  DQS17N  = M_C_DQS_DN<17>
  VSS(70)  = GND
  CB(6)  = M_C_ECC<6>
  VSS(69)  = GND
  CB(2)  = M_C_ECC<2>
  VSS(68)  = GND
  RESET_N  = M_ABC_RST_N
  VDD(25)  = PVDDQ_ABC
  CKE(0)  = M_C_CKE<2>
  VDD(24)  = PVDDQ_ABC
  ACT_N  = M_C_ACT_N
  BG(0)  = M_C_BG<0>
  VDD(23)  = PVDDQ_ABC
  A12  = M_C_MA<12>
  A9  = M_C_MA<9>
  VDD(22)  = PVDDQ_ABC
  A8  = M_C_MA<8>
  A6  = M_C_MA<6>
  VDD(21)  = PVDDQ_ABC
  A3  = M_C_MA<3>
  A1  = M_C_MA<1>
  VDD(20)  = PVDDQ_ABC
  CK0P  = M_C_CLK_DP<2>
  CK0N  = M_C_CLK_DN<2>
  VDD(19)  = PVDDQ_ABC
  VTT(1)  = PVTT_ABC
  EVENT_N  = FM_DIMM_EVENT_COD_N
  A0  = M_C_MA<0>
  VDD(18)  = PVDDQ_ABC
  BA(0)  = M_C_BA<0>
  A16_RAS_N  = M_C_MA<16>
  VDD(17)  = PVDDQ_ABC
  S0_N  = M_C_CS_N<4>
  VDD(16)  = PVDDQ_ABC
  A15_CAS_N  = M_C_MA<15>
  ODT(0)  = M_C_ODT<2>
  VDD(15)  = PVDDQ_ABC
  S1_N  = M_C_CS_N<5>
  VDD(14)  = PVDDQ_ABC
  ODT(1)  = M_C_ODT<3>
  VDD(13)  = PVDDQ_ABC
  S2_N_C(0)  = M_C_CS_N<6>
  VSS(67)  = GND
  DQ(36)  = M_C_DQ<36>
  VSS(66)  = GND
  DQ(32)  = M_C_DQ<32>
  VSS(65)  = GND
  DQS13P  = M_C_DQS_DP<13>
  DQS13N  = M_C_DQS_DN<13>
  VSS(64)  = GND
  DQ(38)  = M_C_DQ<38>
  VSS(63)  = GND
  DQ(34)  = M_C_DQ<34>
  VSS(62)  = GND
  DQ(44)  = M_C_DQ<44>
  VSS(61)  = GND
  DQ(40)  = M_C_DQ<40>
  VSS(60)  = GND
  DQS14P  = M_C_DQS_DP<14>
  DQS14N  = M_C_DQS_DN<14>
  VSS(59)  = GND
  DQ(46)  = M_C_DQ<46>
  VSS(58)  = GND
  DQ(42)  = M_C_DQ<42>
  VSS(57)  = GND
  DQ(52)  = M_C_DQ<52>
  VSS(56)  = GND
  DQ(48)  = M_C_DQ<48>
  VSS(55)  = GND
  DQS15P  = M_C_DQS_DP<15>
  DQS15N  = M_C_DQS_DN<15>
  VSS(54)  = GND
  DQ(54)  = M_C_DQ<54>
  VSS(53)  = GND
  DQ(50)  = M_C_DQ<50>
  VSS(52)  = GND
  DQ(60)  = M_C_DQ<60>
  VSS(51)  = GND
  DQ(56)  = M_C_DQ<56>
  VSS(50)  = GND
  DQS16P  = M_C_DQS_DP<16>
  DQS16N  = M_C_DQS_DN<16>
  VSS(49)  = GND
  DQ(62)  = M_C_DQ<62>
  VSS(48)  = GND
  DQ(58)  = M_C_DQ<58>
  VSS(47)  = GND
  SA(0)  = PVPP_ABC
  SA(1)  = GND
  SCL  = SMB_DDR_ABC_VPP_SCL
  VPP(4)  = PVPP_ABC
  VPP(3)  = PVPP_ABC
  RFU(2)  = TP_CH_C_DIMM_C1_RFU_2
  \12v\(0)  = P12V_NVDIMM_ABC
  VREFCA  = M_C_VREF
  VSS(46)  = GND
  DQ(5)  = M_C_DQ<5>
  VSS(45)  = GND
  DQ(1)  = M_C_DQ<1>
  VSS(44)  = GND
  DQS0N  = M_C_DQS_DN<0>
  DQS0P  = M_C_DQS_DP<0>
  VSS(43)  = GND
  DQ(7)  = M_C_DQ<7>
  VSS(42)  = GND
  DQ(3)  = M_C_DQ<3>
  VSS(41)  = GND
  DQ(13)  = M_C_DQ<13>
  VSS(40)  = GND
  DQ(9)  = M_C_DQ<9>
  VSS(39)  = GND
  DQS1N  = M_C_DQS_DN<1>
  DQS1P  = M_C_DQS_DP<1>
  VSS(38)  = GND
  DQ(15)  = M_C_DQ<15>
  VSS(37)  = GND
  DQ(11)  = M_C_DQ<11>
  VSS(36)  = GND
  DQ(21)  = M_C_DQ<21>
  VSS(35)  = GND
  DQ(17)  = M_C_DQ<17>
  VSS(34)  = GND
  DQS2N  = M_C_DQS_DN<2>
  DQS2P  = M_C_DQS_DP<2>
  VSS(33)  = GND
  DQ(23)  = M_C_DQ<23>
  VSS(32)  = GND
  DQ(19)  = M_C_DQ<19>
  VSS(31)  = GND
  DQ(29)  = M_C_DQ<29>
  VSS(30)  = GND
  DQ(25)  = M_C_DQ<25>
  VSS(29)  = GND
  DQS3N  = M_C_DQS_DN<3>
  DQS3P  = M_C_DQS_DP<3>
  VSS(28)  = GND
  DQ(31)  = M_C_DQ<31>
  VSS(27)  = GND
  DQ(27)  = M_C_DQ<27>
  VSS(26)  = GND
  CB(5)  = M_C_ECC<5>
  VSS(25)  = GND
  CB(1)  = M_C_ECC<1>
  VSS(24)  = GND
  DQS8N  = M_C_DQS_DN<8>
  DQS8P  = M_C_DQS_DP<8>
  VSS(23)  = GND
  CB(7)  = M_C_ECC<7>
  VSS(22)  = GND
  CB(3)  = M_C_ECC<3>
  VSS(21)  = GND
  CKE(1)  = M_C_CKE<3>
  VDD(12)  = PVDDQ_ABC
  RFU(0)  = TP_CH_C_DIMM_C1_RFU_0
  VDD(11)  = PVDDQ_ABC
  BG(1)  = M_C_BG<1>
  ALERT_N  = M_C_ALERT_N
  VDD(10)  = PVDDQ_ABC
  A11  = M_C_MA<11>
  A7  = M_C_MA<7>
  VDD(9)  = PVDDQ_ABC
  A5  = M_C_MA<5>
  A4  = M_C_MA<4>
  VDD(8)  = PVDDQ_ABC
  A2  = M_C_MA<2>
  VDD(7)  = PVDDQ_ABC
  CK1P  = M_C_CLK_DP<3>
  CK1N  = M_C_CLK_DN<3>
  VDD(6)  = PVDDQ_ABC
  VTT(0)  = PVTT_ABC
  PAR  = M_C_PAR
  VDD(5)  = PVDDQ_ABC
  BA(1)  = M_C_BA<1>
  A10  = M_C_MA<10>
  VDD(4)  = PVDDQ_ABC
  RFU(1)  = TP_CH_C_DIMM_C1_RFU_1
  A14_WE_N  = M_C_MA<14>
  VDD(3)  = PVDDQ_ABC
  SAVE_N_NC  = FM_ADR_COMPLETE_ABC_N
  VDD(2)  = PVDDQ_ABC
  A13  = M_C_MA<13>
  VDD(1)  = PVDDQ_ABC
  A17  = M_C_MA<17>
  C(2)  = M_C_C<2>
  VDD(0)  = PVDDQ_ABC
  S3_N_C(1)  = M_C_CS_N<7>
  SA(2)  = PVPP_ABC
  VSS(20)  = GND
  DQ(37)  = M_C_DQ<37>
  VSS(19)  = GND
  DQ(33)  = M_C_DQ<33>
  VSS(18)  = GND
  DQS4N  = M_C_DQS_DN<4>
  DQS4P  = M_C_DQS_DP<4>
  VSS(17)  = GND
  DQ(39)  = M_C_DQ<39>
  VSS(16)  = GND
  DQ(35)  = M_C_DQ<35>
  VSS(15)  = GND
  DQ(45)  = M_C_DQ<45>
  VSS(14)  = GND
  DQ(41)  = M_C_DQ<41>
  VSS(13)  = GND
  DQS5N  = M_C_DQS_DN<5>
  DQS5P  = M_C_DQS_DP<5>
  VSS(12)  = GND
  DQ(47)  = M_C_DQ<47>
  VSS(11)  = GND
  DQ(43)  = M_C_DQ<43>
  VSS(10)  = GND
  DQ(53)  = M_C_DQ<53>
  VSS(9)  = GND
  DQ(49)  = M_C_DQ<49>
  VSS(8)  = GND
  DQS6N  = M_C_DQS_DN<6>
  DQS6P  = M_C_DQS_DP<6>
  VSS(7)  = GND
  DQ(55)  = M_C_DQ<55>
  VSS(6)  = GND
  DQ(51)  = M_C_DQ<51>
  VSS(5)  = GND
  DQ(61)  = M_C_DQ<61>
  VSS(4)  = GND
  DQ(57)  = M_C_DQ<57>
  VSS(3)  = GND
  DQS7N  = M_C_DQS_DN<7>
  DQS7P  = M_C_DQS_DP<7>
  VSS(2)  = GND
  DQ(63)  = M_C_DQ<63>
  VSS(1)  = GND
  DQ(59)  = M_C_DQ<59>
  VSS(0)  = GND
  VDDSPD  = PVPP_ABC
  SDA  = SMB_DDR_ABC_VPP_SDA
  VPP(1)  = PVPP_ABC
  VPP(0)  = PVPP_ABC
  VPP(2)  = PVPP_ABC

(kicad_pcb
	(version 20260206)
	(generator "pcbnew")
	(generator_version "10.0")
	(general
		(thickness 1.6)
		(legacy_teardrops no)
	)
	(paper "A4")
	(title_block
		(title "Wiwynn_Tioga_Pass_MB.brd")
		(comment 1 "Tioga Pass / footprint 2838 of 4770 (J6U2), pads 202-249 of 291")
	)
	(layers
		(0 "F.Cu" signal "TOP")
		(4 "In1.Cu" signal "L2GND")
		(6 "In2.Cu" signal "L3")
		(8 "In3.Cu" signal "L4GND")
		(10 "In4.Cu" signal "L5")
		(12 "In5.Cu" signal "L6GND")
		(14 "In6.Cu" signal "L7VCC")
		(16 "In7.Cu" signal "L8VCC")
		(18 "In8.Cu" signal "L9GND")
		(20 "In9.Cu" signal "L10")
		(22 "In10.Cu" signal "L11GND")
		(24 "In11.Cu" signal "L12")
		(26 "In12.Cu" signal "L13GND")
		(2 "B.Cu" signal "BOTTOM")
		(9 "F.Adhes" user "F.Adhesive")
		(11 "B.Adhes" user "B.Adhesive")
		(13 "F.Paste" user "Package Geometry/Pastemask Top")
		(15 "B.Paste" user "Package Geometry/Pastemask Bottom")
		(5 "F.SilkS" user "Ref Des/Silkscreen Top")
		(7 "B.SilkS" user "Ref Des/Silkscreen Bottom")
		(1 "F.Mask" user "Board Geometry/Soldermask Top")
		(3 "B.Mask" user "Board Geometry/Soldermask Bottom")
		(17 "Dwgs.User" user "User.Drawings")
		(19 "Cmts.User" user "User.Comments")
		(21 "Eco1.User" user "User.Eco1")
		(23 "Eco2.User" user "User.Eco2")
		(25 "Edge.Cuts" user "Board Geometry/Outline")
		(27 "Margin" user)
		(31 "F.CrtYd" user "Package Geometry/Place Bound Top")
		(29 "B.CrtYd" user "Package Geometry/Place Bound Bottom")
		(35 "F.Fab" user "Ref Des/Assembly Top")
		(33 "B.Fab" user "Ref Des/Assembly Bottom")
	)
	(footprint ""
		(layer "B.Cu")
		(at 194.700398 -5.621782 90)
		(property "Reference" "J6U2"
			(at 2.225548 39.48811 0)
			(unlocked yes)
			(layer "B.SilkS")
			(effects
				(font
					(size 0.7874 0.5842)
					(thickness 0.1524)
				)
				(justify left mirror)
			)
		)
		(property "Value" ""
			(at 0 0 90)
			(layer "B.Fab")
			(effects
				(font
					(size 1.27 1.27)
				)
				(justify mirror)
			)
		)
		(duplicate_pad_numbers_are_jumpers no)
		(pad "199" smd rect
			(at -4.59994 45.900086 270)
			(size 1.8034 0.508)
			(layers "B.Cu" "B.Mask" "B.Paste")
			(net "M_C_ECC<7>")
		)
		(pad "200" smd rect
			(at -4.59994 46.74997 270)
			(size 1.8034 0.508)
			(layers "B.Cu" "B.Mask" "B.Paste")
			(net "GND")
		)
		(pad "201" smd rect
			(at -4.59994 47.600108 270)
			(size 1.8034 0.508)
			(layers "B.Cu" "B.Mask" "B.Paste")
			(net "M_C_ECC<3>")
		)
		(pad "202" smd rect
			(at -4.59994 48.449992 270)
			(size 1.8034 0.508)
			(layers "B.Cu" "B.Mask" "B.Paste")
			(net "GND")
		)
		(pad "203" smd rect
			(at -4.59994 49.299876 270)
			(size 1.8034 0.508)
			(layers "B.Cu" "B.Mask" "B.Paste")
			(net "M_C_CKE<3>")
		)
		(pad "204" smd rect
			(at -4.59994 50.150014 270)
			(size 1.8034 0.508)
			(layers "B.Cu" "B.Mask" "B.Paste")
			(net "PVDDQ_ABC")
		)
		(pad "205" smd rect
			(at -4.59994 50.999898 270)
			(size 1.8034 0.508)
			(layers "B.Cu" "B.Mask" "B.Paste")
			(net "TP_CH_C_DIMM_C1_RFU_0")
		)
		(pad "206" smd rect
			(at -4.59994 51.850036 270)
			(size 1.8034 0.508)
			(layers "B.Cu" "B.Mask" "B.Paste")
			(net "PVDDQ_ABC")
		)
		(pad "207" smd rect
			(at -4.59994 52.69992 270)
			(size 1.8034 0.508)
			(layers "B.Cu" "B.Mask" "B.Paste")
			(net "M_C_BG<1>")
		)
		(pad "208" smd rect
			(at -4.59994 53.550058 270)
			(size 1.8034 0.508)
			(layers "B.Cu" "B.Mask" "B.Paste")
			(net "M_C_ALERT_N")
		)
		(pad "209" smd rect
			(at -4.59994 54.399942 270)
			(size 1.8034 0.508)
			(layers "B.Cu" "B.Mask" "B.Paste")
			(net "PVDDQ_ABC")
		)
		(pad "210" smd rect
			(at -4.59994 55.25008 270)
			(size 1.8034 0.508)
			(layers "B.Cu" "B.Mask" "B.Paste")
			(net "M_C_MA<11>")
		)
		(pad "211" smd rect
			(at -4.59994 56.099964 270)
			(size 1.8034 0.508)
			(layers "B.Cu" "B.Mask" "B.Paste")
			(net "M_C_MA<7>")
		)
		(pad "212" smd rect
			(at -4.59994 56.950102 270)
			(size 1.8034 0.508)
			(layers "B.Cu" "B.Mask" "B.Paste")
			(net "PVDDQ_ABC")
		)
		(pad "213" smd rect
			(at -4.59994 57.799986 270)
			(size 1.8034 0.508)
			(layers "B.Cu" "B.Mask" "B.Paste")
			(net "M_C_MA<5>")
		)
		(pad "214" smd rect
			(at -4.59994 58.650124 270)
			(size 1.8034 0.508)
			(layers "B.Cu" "B.Mask" "B.Paste")
			(net "M_C_MA<4>")
		)
		(pad "215" smd rect
			(at -4.59994 59.500008 270)
			(size 1.8034 0.508)
			(layers "B.Cu" "B.Mask" "B.Paste")
			(net "PVDDQ_ABC")
		)
		(pad "216" smd rect
			(at -4.59994 60.349892 270)
			(size 1.8034 0.508)
			(layers "B.Cu" "B.Mask" "B.Paste")
			(net "M_C_MA<2>")
		)
		(pad "217" smd rect
			(at -4.59994 61.20003 270)
			(size 1.8034 0.508)
			(layers "B.Cu" "B.Mask" "B.Paste")
			(net "PVDDQ_ABC")
		)
		(pad "218" smd rect
			(at -4.59994 62.049914 270)
			(size 1.8034 0.508)
			(layers "B.Cu" "B.Mask" "B.Paste")
			(net "M_C_CLK_DP<3>")
		)
		(pad "219" smd rect
			(at -4.59994 62.900052 270)
			(size 1.8034 0.508)
			(layers "B.Cu" "B.Mask" "B.Paste")
			(net "M_C_CLK_DN<3>")
		)
		(pad "220" smd rect
			(at -4.59994 63.749936 270)
			(size 1.8034 0.508)
			(layers "B.Cu" "B.Mask" "B.Paste")
			(net "PVDDQ_ABC")
		)
		(pad "221" smd rect
			(at -4.59994 64.600074 270)
			(size 1.8034 0.508)
			(layers "B.Cu" "B.Mask" "B.Paste")
			(net "PVTT_ABC")
		)
		(pad "222" smd rect
			(at -4.59994 70.550024 270)
			(size 1.8034 0.508)
			(layers "B.Cu" "B.Mask" "B.Paste")
			(net "M_C_PAR")
		)
		(pad "223" smd rect
			(at -4.59994 71.399908 270)
			(size 1.8034 0.508)
			(layers "B.Cu" "B.Mask" "B.Paste")
			(net "PVDDQ_ABC")
		)
		(pad "224" smd rect
			(at -4.59994 72.250046 270)
			(size 1.8034 0.508)
			(layers "B.Cu" "B.Mask" "B.Paste")
			(net "M_C_BA<1>")
		)
		(pad "225" smd rect
			(at -4.59994 73.09993 270)
			(size 1.8034 0.508)
			(layers "B.Cu" "B.Mask" "B.Paste")
			(net "M_C_MA<10>")
		)
		(pad "226" smd rect
			(at -4.59994 73.950068 270)
			(size 1.8034 0.508)
			(layers "B.Cu" "B.Mask" "B.Paste")
			(net "PVDDQ_ABC")
		)
		(pad "227" smd rect
			(at -4.59994 74.799952 270)
			(size 1.8034 0.508)
			(layers "B.Cu" "B.Mask" "B.Paste")
			(net "TP_CH_C_DIMM_C1_RFU_1")
		)
		(pad "228" smd rect
			(at -4.59994 75.65009 270)
			(size 1.8034 0.508)
			(layers "B.Cu" "B.Mask" "B.Paste")
			(net "M_C_MA<14>")
		)
		(pad "229" smd rect
			(at -4.59994 76.499974 270)
			(size 1.8034 0.508)
			(layers "B.Cu" "B.Mask" "B.Paste")
			(net "PVDDQ_ABC")
		)
		(pad "230" smd rect
			(at -4.59994 77.350112 270)
			(size 1.8034 0.508)
			(layers "B.Cu" "B.Mask" "B.Paste")
			(net "FM_ADR_COMPLETE_ABC_N")
		)
		(pad "231" smd rect
			(at -4.59994 78.199996 270)
			(size 1.8034 0.508)
			(layers "B.Cu" "B.Mask" "B.Paste")
			(net "PVDDQ_ABC")
		)
		(pad "232" smd rect
			(at -4.59994 79.04988 270)
			(size 1.8034 0.508)
			(layers "B.Cu" "B.Mask" "B.Paste")
			(net "M_C_MA<13>")
		)
		(pad "233" smd rect
			(at -4.59994 79.900018 270)
			(size 1.8034 0.508)
			(layers "B.Cu" "B.Mask" "B.Paste")
			(net "PVDDQ_ABC")
		)
		(pad "234" smd rect
			(at -4.59994 80.749902 270)
			(size 1.8034 0.508)
			(layers "B.Cu" "B.Mask" "B.Paste")
			(net "M_C_MA<17>")
		)
		(pad "235" smd rect
			(at -4.59994 81.60004 270)
			(size 1.8034 0.508)
			(layers "B.Cu" "B.Mask" "B.Paste")
			(net "M_C_C<2>")
		)
		(pad "236" smd rect
			(at -4.59994 82.449924 270)
			(size 1.8034 0.508)
			(layers "B.Cu" "B.Mask" "B.Paste")
			(net "PVDDQ_ABC")
		)
		(pad "237" smd rect
			(at -4.59994 83.300062 270)
			(size 1.8034 0.508)
			(layers "B.Cu" "B.Mask" "B.Paste")
			(net "M_C_CS_N<7>")
		)
		(pad "238" smd rect
			(at -4.59994 84.149946 270)
			(size 1.8034 0.508)
			(layers "B.Cu" "B.Mask" "B.Paste")
			(net "PVPP_ABC")
		)
		(pad "239" smd rect
			(at -4.59994 85.000084 270)
			(size 1.8034 0.508)
			(layers "B.Cu" "B.Mask" "B.Paste")
			(net "GND")
		)
		(pad "240" smd rect
			(at -4.59994 85.849968 270)
			(size 1.8034 0.508)
			(layers "B.Cu" "B.Mask" "B.Paste")
			(net "M_C_DQ<37>")
		)
		(pad "241" smd rect
			(at -4.59994 86.700106 270)
			(size 1.8034 0.508)
			(layers "B.Cu" "B.Mask" "B.Paste")
			(net "GND")
		)
		(pad "242" smd rect
			(at -4.59994 87.54999 270)
			(size 1.8034 0.508)
			(layers "B.Cu" "B.Mask" "B.Paste")
			(net "M_C_DQ<33>")
		)
		(pad "243" smd rect
			(at -4.59994 88.399874 270)
			(size 1.8034 0.508)
			(layers "B.Cu" "B.Mask" "B.Paste")
			(net "GND")
		)
		(pad "244" smd rect
			(at -4.59994 89.250012 270)
			(size 1.8034 0.508)
			(layers "B.Cu" "B.Mask" "B.Paste")
			(net "M_C_DQS_DN<4>")
		)
		(pad "245" smd rect
			(at -4.59994 90.099896 270)
			(size 1.8034 0.508)
			(layers "B.Cu" "B.Mask" "B.Paste")
			(net "M_C_DQS_DP<4>")
		)
		(pad "246" smd rect
			(at -4.59994 90.950034 270)
			(size 1.8034 0.508)
			(layers "B.Cu" "B.Mask" "B.Paste")
			(net "GND")
		)
	)
)
